(kicad_pcb
	(version 20241229)
	(generator "pcbnew")
	(generator_version "9.0")
	(general
		(thickness 1.294)
		(legacy_teardrops no)
	)
	(paper "A3")
	(title_block
		(title "Kintex 410T devboard")
		(date "2024-04-03")
		(rev "1.1.2")
		(comment 9 "footprints 277-281 of 975")
	)
	(layers
		(0 "F.Cu" mixed)
		(4 "In1.Cu" power)
		(6 "In2.Cu" power)
		(8 "In3.Cu" mixed)
		(10 "In4.Cu" power)
		(12 "In5.Cu" mixed)
		(14 "In6.Cu" power)
		(16 "In7.Cu" mixed)
		(18 "In8.Cu" power)
		(2 "B.Cu" mixed)
		(9 "F.Adhes" user "F.Adhesive")
		(11 "B.Adhes" user "B.Adhesive")
		(13 "F.Paste" user)
		(15 "B.Paste" user)
		(5 "F.SilkS" user "F.Silkscreen")
		(7 "B.SilkS" user "B.Silkscreen")
		(1 "F.Mask" user)
		(3 "B.Mask" user)
		(17 "Dwgs.User" user "User.Drawings")
		(19 "Cmts.User" user "User.Comments")
		(21 "Eco1.User" user "User.Eco1")
		(23 "Eco2.User" user "User.Eco2")
		(25 "Edge.Cuts" user)
		(27 "Margin" user)
		(31 "F.CrtYd" user "F.Courtyard")
		(29 "B.CrtYd" user "B.Courtyard")
		(35 "F.Fab" user)
		(33 "B.Fab" user)
	)
	(footprint "antmicro-footprints:R_0402_1005Metric"
		(layer "F.Cu")
		(at 236.2 131.55 180)
		(descr "Resistor SMD 0402")
		(tags "resistor SMD 0402")
		(property "Reference" "R177"
			(at 1.825 3.525 180)
			(layer "F.SilkS")
			(effects
				(font
					(size 0.7 0.7)
					(thickness 0.15)
				)
				(justify left bottom)
			)
		)
		(property "Value" "R_33R_0402"
			(at 0 1.4 180)
			(layer "F.Fab")
			(effects
				(font
					(size 0.7 0.7)
					(thickness 0.15)
				)
				(justify left bottom)
			)
		)
		(property "Description" "SMD Chip Resistor, 33 ohm, ± 1%, 62.5 mW, 0402 [1005 Metric], Thick Film, General Purpose"
			(at 0 0 180)
			(layer "F.Fab")
			(hide yes)
			(effects
				(font
					(size 1.27 1.27)
					(thickness 0.15)
				)
			)
		)
		(property "Author" "Antmicro"
			(at 472.4 263.1 0)
			(layer "F.Fab")
			(hide yes)
			(effects
				(font
					(size 1 1)
					(thickness 0.15)
				)
			)
		)
		(property "License" "Apache-2.0"
			(at 472.4 263.1 0)
			(layer "F.Fab")
			(hide yes)
			(effects
				(font
					(size 1 1)
					(thickness 0.15)
				)
			)
		)
		(property "MPN" "CR0402-FX-33R0GLF"
			(at 472.4 263.1 0)
			(layer "F.Fab")
			(hide yes)
			(effects
				(font
					(size 1 1)
					(thickness 0.15)
				)
			)
		)
		(property "Manufacturer" "Bourns"
			(at 472.4 263.1 0)
			(layer "F.Fab")
			(hide yes)
			(effects
				(font
					(size 1 1)
					(thickness 0.15)
				)
			)
		)
		(property "Tolerance" "1%"
			(at 472.4 263.1 0)
			(layer "F.Fab")
			(hide yes)
			(effects
				(font
					(size 1 1)
					(thickness 0.15)
				)
			)
		)
		(property "Val" "33R"
			(at 472.4 263.1 0)
			(layer "F.Fab")
			(hide yes)
			(effects
				(font
					(size 1 1)
					(thickness 0.15)
				)
			)
		)
		(sheetname "USB PHY")
		(sheetfile "usb-phy.kicad_sch")
		(attr smd)
		(fp_rect
			(start -0.925 -0.47)
			(end 0.925 0.47)
			(stroke
				(width 0.05)
				(type default)
			)
			(fill no)
			(layer "F.CrtYd")
		)
		(fp_rect
			(start -0.5 -0.25)
			(end 0.5 0.25)
			(stroke
				(width 0.15)
				(type solid)
			)
			(fill no)
			(layer "F.Fab")
		)
		(pad "1" smd roundrect
			(at -0.48 0 180)
			(size 0.59 0.64)
			(layers "F.Cu" "F.Mask" "F.Paste")
			(roundrect_rratio 0.25)
			(net 369 "Net-(U22-B2Y)")
			(pintype "passive")
		)
		(pad "2" smd roundrect
			(at 0.48 0 180)
			(size 0.59 0.64)
			(layers "F.Cu" "F.Mask" "F.Paste")
			(roundrect_rratio 0.25)
			(net 161 "/FPGA Config/JTAG.TMS")
			(pintype "passive")
		)
	)
	(footprint "antmicro-footprints:R_Array_4x0201_Panasonic_EXB18V"
		(layer "F.Cu")
		(at 249.9 144.302)
		(property "Reference" "R44"
			(at -15.7 -39.952 0)
			(layer "F.SilkS")
			(effects
				(font
					(size 0.7 0.7)
					(thickness 0.15)
				)
				(justify right bottom)
			)
		)
		(property "Value" "R_4x33R_0201_array"
			(at -1.1 1.8 0)
			(layer "F.Fab")
			(effects
				(font
					(size 0.7 0.7)
					(thickness 0.15)
				)
				(justify left bottom)
			)
		)
		(property "Description" "Fixed Network Resistor, 33 ohm, Isolated, 4 Resistors, 0502 [1406 Metric], Flat, ± 5%"
			(at 0 0 0)
			(layer "F.Fab")
			(hide yes)
			(effects
				(font
					(size 1.27 1.27)
					(thickness 0.15)
				)
			)
		)
		(property "Author" "Antmicro"
			(at 0 0 0)
			(layer "F.Fab")
			(hide yes)
			(effects
				(font
					(size 1 1)
					(thickness 0.15)
				)
			)
		)
		(property "License" "Apache-2.0"
			(at 0 0 0)
			(layer "F.Fab")
			(hide yes)
			(effects
				(font
					(size 1 1)
					(thickness 0.15)
				)
			)
		)
		(property "MPN" "EXB-18V330JX"
			(at 0 0 0)
			(layer "F.Fab")
			(hide yes)
			(effects
				(font
					(size 1 1)
					(thickness 0.15)
				)
			)
		)
		(property "Manufacturer" "Panasonic"
			(at 0 0 0)
			(layer "F.Fab")
			(hide yes)
			(effects
				(font
					(size 1 1)
					(thickness 0.15)
				)
			)
		)
		(property "Val" "R_4x33R_0201"
			(at 0 0 0)
			(layer "F.Fab")
			(hide yes)
			(effects
				(font
					(size 1 1)
					(thickness 0.15)
				)
			)
		)
		(sheetname "Supervisior MCU")
		(sheetfile "supervisor-mcu.kicad_sch")
		(attr smd)
		(fp_line
			(start -0.8 -0.45)
			(end -0.8 0.45)
			(stroke
				(width 0.12)
				(type solid)
			)
			(layer "F.SilkS")
		)
		(fp_line
			(start 0.8 -0.45)
			(end 0.8 0.45)
			(stroke
				(width 0.12)
				(type solid)
			)
			(layer "F.SilkS")
		)
		(fp_rect
			(start -0.898 -0.66)
			(end 0.898 0.65)
			(stroke
				(width 0.05)
				(type solid)
			)
			(fill no)
			(layer "F.CrtYd")
		)
		(pad "1" smd roundrect
			(at -0.6 0.298)
			(size 0.2 0.4)
			(layers "F.Cu" "F.Mask" "F.Paste")
			(roundrect_rratio 0.25)
			(net 1104 "/Supervisior MCU/FPGA_M1")
			(pinfunction "R1.1")
			(pintype "passive")
		)
		(pad "2" smd roundrect
			(at -0.202 0.298)
			(size 0.2 0.4)
			(layers "F.Cu" "F.Mask" "F.Paste")
			(roundrect_rratio 0.25)
			(net 260 "/Supervisior MCU/FPGA_CFG_CS")
			(pinfunction "R2.1")
			(pintype "passive")
		)
		(pad "3" smd roundrect
			(at 0.2 0.298)
			(size 0.2 0.4)
			(layers "F.Cu" "F.Mask" "F.Paste")
			(roundrect_rratio 0.25)
			(net 1092 "/Supervisior MCU/USB_CLK1_SPARE")
			(pinfunction "R3.1")
			(pintype "passive")
		)
		(pad "4" smd roundrect
			(at 0.598 0.298)
			(size 0.2 0.4)
			(layers "F.Cu" "F.Mask" "F.Paste")
			(roundrect_rratio 0.25)
			(net 1117 "/Supervisior MCU/USB_SPARE3")
			(pinfunction "R4.1")
			(pintype "passive")
		)
		(pad "5" smd roundrect
			(at 0.598 -0.3)
			(size 0.2 0.4)
			(layers "F.Cu" "F.Mask" "F.Paste")
			(roundrect_rratio 0.25)
			(net 1385 "/SUP_MCU.SPARE3")
			(pinfunction "R4.2")
			(pintype "passive")
		)
		(pad "6" smd roundrect
			(at 0.2 -0.3)
			(size 0.2 0.4)
			(layers "F.Cu" "F.Mask" "F.Paste")
			(roundrect_rratio 0.25)
			(net 1386 "/SUP_MCU.SCLK1")
			(pinfunction "R3.2")
			(pintype "passive")
		)
		(pad "7" smd roundrect
			(at -0.202 -0.3)
			(size 0.2 0.4)
			(layers "F.Cu" "F.Mask" "F.Paste")
			(roundrect_rratio 0.25)
			(net 1334 "/SUP_MCU.CFG_CS")
			(pinfunction "R2.2")
			(pintype "passive")
		)
		(pad "8" smd roundrect
			(at -0.6 -0.3)
			(size 0.2 0.4)
			(layers "F.Cu" "F.Mask" "F.Paste")
			(roundrect_rratio 0.25)
			(net 1313 "/SUP_MCU.FPGA_M1")
			(pinfunction "R1.2")
			(pintype "passive")
		)
	)
	(footprint "antmicro-footprints:R_0603_1608Metric"
		(layer "F.Cu")
		(at 183 172.7 90)
		(descr "Resistor SMD 0603")
		(tags "resistor SMD 0603")
		(property "Reference" "R291"
			(at -1.39 1.37 270)
			(layer "F.SilkS")
			(effects
				(font
					(size 0.7 0.7)
					(thickness 0.15)
				)
				(justify left bottom)
			)
		)
		(property "Value" "R_0R_22.4A_0603"
			(at 0 1.6 90)
			(layer "F.Fab")
			(effects
				(font
					(size 0.7 0.7)
					(thickness 0.15)
				)
				(justify left bottom)
			)
		)
		(property "Description" "SMD Chip Resistor"
			(at 0 0 90)
			(layer "F.Fab")
			(hide yes)
			(effects
				(font
					(size 1.27 1.27)
					(thickness 0.15)
				)
			)
		)
		(property "Author" "Antmicro"
			(at 355.7 -10.3 0)
			(layer "F.Fab")
			(hide yes)
			(effects
				(font
					(size 1 1)
					(thickness 0.15)
				)
			)
		)
		(property "License" "Apache-2.0"
			(at 355.7 -10.3 0)
			(layer "F.Fab")
			(hide yes)
			(effects
				(font
					(size 1 1)
					(thickness 0.15)
				)
			)
		)
		(property "MPN" "PMR03EZPJ000"
			(at 355.7 -10.3 0)
			(layer "F.Fab")
			(hide yes)
			(effects
				(font
					(size 1 1)
					(thickness 0.15)
				)
			)
		)
		(property "Manufacturer" "ROHM Semiconductor"
			(at 355.7 -10.3 0)
			(layer "F.Fab")
			(hide yes)
			(effects
				(font
					(size 1 1)
					(thickness 0.15)
				)
			)
		)
		(property "Max. Curr." "22.4A"
			(at 355.7 -10.3 0)
			(layer "F.Fab")
			(hide yes)
			(effects
				(font
					(size 1 1)
					(thickness 0.15)
				)
			)
		)
		(property "Tolerance" "template_tolerance"
			(at 355.7 -10.3 0)
			(layer "F.Fab")
			(hide yes)
			(effects
				(font
					(size 1 1)
					(thickness 0.15)
				)
			)
		)
		(property "Val" "0R"
			(at 355.7 -10.3 0)
			(layer "F.Fab")
			(hide yes)
			(effects
				(font
					(size 1 1)
					(thickness 0.15)
				)
			)
		)
		(sheetname "DC-DC Converters")
		(sheetfile "dc-dc.kicad_sch")
		(attr smd)
		(fp_line
			(start -0.15 -0.4)
			(end 0.15 -0.4)
			(stroke
				(width 0.15)
				(type solid)
			)
			(layer "F.SilkS")
		)
		(fp_line
			(start -0.15 0.4)
			(end 0.15 0.4)
			(stroke
				(width 0.15)
				(type solid)
			)
			(layer "F.SilkS")
		)
		(fp_rect
			(start -1.25 -0.65)
			(end 1.25 0.65)
			(stroke
				(width 0.05)
				(type solid)
			)
			(fill no)
			(layer "F.CrtYd")
		)
		(fp_rect
			(start -0.8 -0.4)
			(end 0.8 0.4)
			(stroke
				(width 0.15)
				(type solid)
			)
			(fill no)
			(layer "F.Fab")
		)
		(pad "1" smd roundrect
			(at -0.7 0 90)
			(size 0.8 1)
			(layers "F.Cu" "F.Mask" "F.Paste")
			(roundrect_rratio 0.2)
			(net 739 "/DC-DC Converters/5V_local")
			(pintype "passive")
		)
		(pad "2" smd roundrect
			(at 0.7 0 90)
			(size 0.8 1)
			(layers "F.Cu" "F.Mask" "F.Paste")
			(roundrect_rratio 0.2)
			(net 703 "+5V")
			(pintype "passive")
		)
	)
	(footprint "antmicro-footprints:PinSocket_2x6_P2.54mm_Drill1.04mm_Horizontal"
		(layer "F.Cu")
		(at 213.4375 80.1495)
		(property "Reference" "J5"
			(at 14.3625 -1.9495 0)
			(layer "F.SilkS")
			(effects
				(font
					(size 0.7 0.7)
					(thickness 0.15)
				)
				(justify left bottom)
			)
		)
		(property "Value" "PinSocket_2x6_P2.54mm_Drill1.04mm_Horizontal"
			(at 0 4.75 0)
			(layer "F.Fab")
			(effects
				(font
					(size 0.7 0.7)
					(thickness 0.15)
				)
				(justify left bottom)
			)
		)
		(property "Description" "PCB Receptacle, Board-to-Board, 2.54 mm, 2 Rows, 12 Contacts, Through Hole Mount Right Angle, SSW"
			(at 0 0 0)
			(layer "F.Fab")
			(hide yes)
			(effects
				(font
					(size 1.27 1.27)
					(thickness 0.15)
				)
			)
		)
		(property "Author" "Antmicro"
			(at 0 0 0)
			(layer "F.Fab")
			(hide yes)
			(effects
				(font
					(size 1 1)
					(thickness 0.15)
				)
			)
		)
		(property "License" "Apache-2.0"
			(at 0 0 0)
			(layer "F.Fab")
			(hide yes)
			(effects
				(font
					(size 1 1)
					(thickness 0.15)
				)
			)
		)
		(property "MPN" "SSW-106-02-G-D-RA"
			(at 0 0 0)
			(layer "F.Fab")
			(hide yes)
			(effects
				(font
					(size 1 1)
					(thickness 0.15)
				)
			)
		)
		(property "Manufacturer" "Samtec"
			(at 0 0 0)
			(layer "F.Fab")
			(hide yes)
			(effects
				(font
					(size 1 1)
					(thickness 0.15)
				)
			)
		)
		(sheetname "User GPIO + LED + button + DIP switch")
		(sheetfile "user-gpio.kicad_sch")
		(attr through_hole)
		(fp_line
			(start -1.526 -1.524)
			(end -1.526 -10.035)
			(stroke
				(width 0.15)
				(type solid)
			)
			(layer "F.SilkS")
		)
		(fp_line
			(start 14.223 -10.035)
			(end -1.526 -10.035)
			(stroke
				(width 0.15)
				(type solid)
			)
			(layer "F.SilkS")
		)
		(fp_line
			(start 14.223 -10.035)
			(end 14.223 -1.524)
			(stroke
				(width 0.15)
				(type solid)
			)
			(layer "F.SilkS")
		)
		(fp_line
			(start 14.223 -1.524)
			(end -1.526 -1.524)
			(stroke
				(width 0.15)
				(type solid)
			)
			(layer "F.SilkS")
		)
		(fp_circle
			(center -1.2 0)
			(end -1.15 0)
			(stroke
				(width 0.15)
				(type solid)
			)
			(fill yes)
			(layer "F.SilkS")
		)
		(fp_rect
			(start -1.9 -10.4)
			(end 14.6 3.6)
			(stroke
				(width 0.05)
				(type solid)
			)
			(fill no)
			(layer "F.CrtYd")
		)
		(fp_line
			(start -1.526 -10.035)
			(end 14.223 -10.035)
			(stroke
				(width 0.15)
				(type solid)
			)
			(layer "F.Fab")
		)
		(fp_line
			(start -1.526 -10.035)
			(end 14.223 -10.035)
			(stroke
				(width 0.15)
				(type solid)
			)
			(layer "F.Fab")
		)
		(fp_line
			(start -1.526 -1.524)
			(end -1.526 -10.035)
			(stroke
				(width 0.15)
				(type solid)
			)
			(layer "F.Fab")
		)
		(fp_line
			(start -1.526 -1.524)
			(end -1.526 -10.035)
			(stroke
				(width 0.15)
				(type solid)
			)
			(layer "F.Fab")
		)
		(fp_line
			(start 14.223 -10.035)
			(end 14.223 -1.524)
			(stroke
				(width 0.15)
				(type solid)
			)
			(layer "F.Fab")
		)
		(fp_line
			(start 14.223 -10.035)
			(end 14.223 -1.524)
			(stroke
				(width 0.15)
				(type solid)
			)
			(layer "F.Fab")
		)
		(fp_line
			(start 14.223 -1.524)
			(end -1.526 -1.524)
			(stroke
				(width 0.15)
				(type solid)
			)
			(layer "F.Fab")
		)
		(pad "1" thru_hole rect
			(at 0 0)
			(size 1.84 1.84)
			(drill 1.04)
			(layers "*.Cu" "*.Mask")
			(remove_unused_layers no)
			(net 808 "/User GPIO + LED + button + DIP switch/PMOD_A_7")
			(pintype "passive")
		)
		(pad "2" thru_hole circle
			(at 0 2.539)
			(size 1.84 1.84)
			(drill 1.04)
			(layers "*.Cu" "*.Mask")
			(remove_unused_layers no)
			(net 809 "/User GPIO + LED + button + DIP switch/PMOD_A_1")
			(pintype "passive")
		)
		(pad "3" thru_hole circle
			(at 2.539 0)
			(size 1.84 1.84)
			(drill 1.04)
			(layers "*.Cu" "*.Mask")
			(remove_unused_layers no)
			(net 806 "/User GPIO + LED + button + DIP switch/PMOD_A_8")
			(pintype "passive")
		)
		(pad "4" thru_hole circle
			(at 2.539 2.539)
			(size 1.8 1.8)
			(drill 1.04)
			(layers "*.Cu" "*.Mask")
			(remove_unused_layers no)
			(net 807 "/User GPIO + LED + button + DIP switch/PMOD_A_2")
			(pintype "passive")
		)
		(pad "5" thru_hole circle
			(at 5.078 0)
			(size 1.84 1.84)
			(drill 1.04)
			(layers "*.Cu" "*.Mask")
			(remove_unused_layers no)
			(net 804 "/User GPIO + LED + button + DIP switch/PMOD_A_9")
			(pintype "passive")
		)
		(pad "6" thru_hole circle
			(at 5.078 2.539)
			(size 1.84 1.84)
			(drill 1.04)
			(layers "*.Cu" "*.Mask")
			(remove_unused_layers no)
			(net 805 "/User GPIO + LED + button + DIP switch/PMOD_A_3")
			(pintype "passive")
		)
		(pad "7" thru_hole circle
			(at 7.618 0)
			(size 1.84 1.84)
			(drill 1.04)
			(layers "*.Cu" "*.Mask")
			(remove_unused_layers no)
			(net 802 "/User GPIO + LED + button + DIP switch/PMOD_A_10")
			(pintype "passive")
		)
		(pad "8" thru_hole circle
			(at 7.618 2.539)
			(size 1.84 1.84)
			(drill 1.04)
			(layers "*.Cu" "*.Mask")
			(remove_unused_layers no)
			(net 803 "/User GPIO + LED + button + DIP switch/PMOD_A_4")
			(pintype "passive")
		)
		(pad "9" thru_hole circle
			(at 10.159 0)
			(size 1.84 1.84)
			(drill 1.04)
			(layers "*.Cu" "*.Mask")
			(remove_unused_layers no)
			(net 1 "GND")
			(pintype "passive")
		)
		(pad "10" thru_hole circle
			(at 10.159 2.539)
			(size 1.84 1.84)
			(drill 1.04)
			(layers "*.Cu" "*.Mask")
			(remove_unused_layers no)
			(net 1 "GND")
			(pintype "passive")
		)
		(pad "11" thru_hole circle
			(at 12.698 0)
			(size 1.84 1.84)
			(drill 1.04)
			(layers "*.Cu" "*.Mask")
			(remove_unused_layers no)
			(net 24 "+3V3")
			(pintype "passive")
		)
		(pad "12" thru_hole circle
			(at 12.698 2.539)
			(size 1.84 1.84)
			(drill 1.04)
			(layers "*.Cu" "*.Mask")
			(remove_unused_layers no)
			(net 24 "+3V3")
			(pintype "passive")
		)
	)
	(footprint "antmicro-footprints:FB_0805_2012Metric"
		(layer "F.Cu")
		(at 237 179)
		(descr "FERRITE BEAD 0805")
		(tags "FERRITE BEAD 0805")
		(property "Reference" "FB2"
			(at -1 1.9 0)
			(layer "F.SilkS")
			(effects
				(font
					(size 0.7 0.7)
					(thickness 0.15)
				)
				(justify left bottom)
			)
		)
		(property "Value" "FB_220Z_2A_Murata-BLM21PG_0805"
			(at 0 1.8 0)
			(layer "F.Fab")
			(effects
				(font
					(size 0.7 0.7)
					(thickness 0.15)
				)
				(justify left bottom)
			)
		)
		(property "Description" "Ferrite Bead, 0805 [2012 Metric], 220 ohm, 2 A, BLM21, 0.045 ohm, ± 25%, DC power line"
			(at 0 0 0)
			(layer "F.Fab")
			(hide yes)
			(effects
				(font
					(size 1.27 1.27)
					(thickness 0.15)
				)
			)
		)
		(property "Author" "Antmicro"
			(at 0 0 0)
			(layer "F.Fab")
			(hide yes)
			(effects
				(font
					(size 1 1)
					(thickness 0.15)
				)
			)
		)
		(property "Current" ""
			(at 0 0 0)
			(layer "F.Fab")
			(hide yes)
			(effects
				(font
					(size 1 1)
					(thickness 0.15)
				)
			)
		)
		(property "License" "Apache-2.0"
			(at 0 0 0)
			(layer "F.Fab")
			(hide yes)
			(effects
				(font
					(size 1 1)
					(thickness 0.15)
				)
			)
		)
		(property "MPN" "BLM21PG221SN1D"
			(at 0 0 0)
			(layer "F.Fab")
			(hide yes)
			(effects
				(font
					(size 1 1)
					(thickness 0.15)
				)
			)
		)
		(property "Manufacturer" "Murata"
			(at 0 0 0)
			(layer "F.Fab")
			(hide yes)
			(effects
				(font
					(size 1 1)
					(thickness 0.15)
				)
			)
		)
		(property "Val" "220Z/2A"
			(at 0 0 0)
			(layer "F.Fab")
			(hide yes)
			(effects
				(font
					(size 1 1)
					(thickness 0.15)
				)
			)
		)
		(sheetname "Power supply")
		(sheetfile "power-supply.kicad_sch")
		(attr smd)
		(fp_line
			(start -0.319 0.698)
			(end 0.281 0.698)
			(stroke
				(width 0.15)
				(type solid)
			)
			(layer "F.SilkS")
		)
		(fp_line
			(start -0.299 -0.698)
			(end 0.299 -0.698)
			(stroke
				(width 0.15)
				(type solid)
			)
			(layer "F.SilkS")
		)
		(fp_rect
			(start 1.95 -0.9)
			(end -1.95 0.9)
			(stroke
				(width 0.05)
				(type default)
			)
			(fill no)
			(layer "F.CrtYd")
		)
		(fp_line
			(start -0.948 -0.681)
			(end 0.948 -0.681)
			(stroke
				(width 0.15)
				(type solid)
			)
			(layer "F.Fab")
		)
		(fp_line
			(start -0.948 -0.676)
			(end -0.948 0.676)
			(stroke
				(width 0.15)
				(type solid)
			)
			(layer "F.Fab")
		)
		(fp_line
			(start -0.948 0.681)
			(end 0.948 0.681)
			(stroke
				(width 0.15)
				(type solid)
			)
			(layer "F.Fab")
		)
		(fp_line
			(start 0.948 -0.676)
			(end 0.948 0.676)
			(stroke
				(width 0.15)
				(type solid)
			)
			(layer "F.Fab")
		)
		(pad "1" smd roundrect
			(at -1.1 0)
			(size 1.2 1.3)
			(layers "F.Cu" "F.Mask" "F.Paste")
			(roundrect_rratio 0.25)
			(net 756 "Net-(D4-Pad1)")
			(pintype "passive")
		)
		(pad "2" smd roundrect
			(at 1.1 0)
			(size 1.2 1.3)
			(layers "F.Cu" "F.Mask" "F.Paste")
			(roundrect_rratio 0.25)
			(net 697 "/Power supply/VSS")
			(pintype "passive")
		)
	)
)
